FILE_TYPE = MULTI_PHYS_TABLE;

PART 'GL852GOHY60'

{========================================================================================}
:VALUE          | PART_TYPE | MATERIAL | PART_NUMBER    = STANDARD | LIFECYCLE      | PART_NUMBER   | JEDEC_TYPE   | DESCRIPTION                      | MANUFTR | MANUF_PN       | RD_CMPLS_LVL | CMPLS_LVL | FROM_PJ     | CLASS | DIP_SMD | DATA                   | EE_CHECK_LIST | FP_ECN             | PSL | CREATOR | STATUS | MSD | ESD_CDM | ESD_HBM | ESD_MM | PIN_LENGTH_SHORT_PIN | PIN_LENGTH_LONG_PIN | CREATEDAY  ;
{========================================================================================}
 'GL852G-OHY60' | 'SMLF'    | 'IC'     | 'AL000852001'(!) = ''       | ''               | 'AL000852001' |'QFN28_THXL'| 'IC CTRL(28P) GL852G-OHY60(QFN)' | 'GSL'   | 'GL852G-OHY60' | 'EP(V1)'     | 'EP(V1)'  | 'T6UA-CART' | 'IC'  | ''      | 'GSL_GL852G-OHY60.pdf' | ''            | 'GL852G-OHY60.msg' | ''  | ''      | ''     | ''  | ''      | ''      | ''     | '0 MILS'             | '0 MILS'            | '20210927'
 'GL852G-OHY60' | 'SMLF'    | 'EMPTY'  | 'AL000852001'(!) = ''       | ''               | 'AL000852001' |'QFN28_THXL'| 'IC CTRL(28P) GL852G-OHY60(QFN)' | 'GSL'   | 'GL852G-OHY60' | 'EP(V1)'     | 'EP(V1)'  | 'T6UA-CART' | 'IC'  | ''      | 'GSL_GL852G-OHY60.pdf' | ''            | 'GL852G-OHY60.msg' | ''  | ''      | ''     | ''  | ''      | ''      | ''     | '0 MILS'             | '0 MILS'            | '20210927'

END_PART

END.

